FILE_TYPE = MACRO_DRAWING;
SET COLOR_WIRE YELLOW;
SET COLOR_PROP ORANGE;
SET COLOR_DOT WHITE;
SET COLOR_ARC YELLOW;
SET COLOR_BODY GREEN;
SET COLOR_NOTE PURPLE;
SET PROP_DISPLAY VALUE;
SET PAGE_NUMBER P34;
FORCEADD OFFPAGE..2
(-600 5925);
FORCEPROP 2 LAST $XR1 79 
J 0
(-321 5925);
DISPLAY 0.638298 (-321 5925);
PAINT MONO (-321 5925);
FORCEPROP 2 LAST $XR0 34 
J 0
(-411 5925);
DISPLAY 0.638298 (-411 5925);
PAINT MONO (-411 5925);
FORCEPROP 2 LAST CDS_LIB standard
J 0
(-600 5925);
DISPLAY INVISIBLE (-600 5925);
FORCEPROP 1 LAST OFFPAGE TRUE
J 0
(-275 5800);
DISPLAY 0.872340 (-275 5800);
PAINT GREEN (-275 5800);
DISPLAY INVISIBLE (-275 5800);
FORCEPROP 1 LAST COMMENT_BODY TRUE
J 0
(-645 5830);
DISPLAY 0.872340 (-645 5830);
PAINT GREEN (-645 5830);
DISPLAY INVISIBLE (-645 5830);
FORCEPROP 2 LAST PATH I1
J 0
(-300 5975);
DISPLAY 0.680851 (-300 5975);
DISPLAY INVISIBLE (-300 5975);
FORCEADD OFFPAGE..2
(-525 4925);
FORCEPROP 2 LAST $XR1 34 
J 0
(-246 4925);
DISPLAY 0.638298 (-246 4925);
PAINT MONO (-246 4925);
FORCEPROP 2 LAST $XR0 28 
J 0
(-336 4925);
DISPLAY 0.638298 (-336 4925);
PAINT MONO (-336 4925);
FORCEPROP 2 LAST CDS_LIB standard
J 0
(-525 4925);
DISPLAY INVISIBLE (-525 4925);
FORCEPROP 1 LAST OFFPAGE TRUE
J 0
(-200 4800);
DISPLAY 0.872340 (-200 4800);
PAINT GREEN (-200 4800);
DISPLAY INVISIBLE (-200 4800);
FORCEPROP 1 LAST COMMENT_BODY TRUE
J 0
(-570 4830);
DISPLAY 0.872340 (-570 4830);
PAINT GREEN (-570 4830);
DISPLAY INVISIBLE (-570 4830);
FORCEPROP 2 LAST PATH I104
J 0
(-225 4975);
DISPLAY 0.680851 (-225 4975);
DISPLAY INVISIBLE (-225 4975);
FORCEADD OFFPAGE..2
(-525 4850);
FORCEPROP 2 LAST $XR1 34 
J 0
(-246 4850);
DISPLAY 0.638298 (-246 4850);
PAINT MONO (-246 4850);
FORCEPROP 2 LAST $XR0 28 
J 0
(-336 4850);
DISPLAY 0.638298 (-336 4850);
PAINT MONO (-336 4850);
FORCEPROP 2 LAST CDS_LIB standard
J 0
(-525 4850);
DISPLAY INVISIBLE (-525 4850);
FORCEPROP 1 LAST OFFPAGE TRUE
J 0
(-200 4725);
DISPLAY 0.872340 (-200 4725);
PAINT GREEN (-200 4725);
DISPLAY INVISIBLE (-200 4725);
FORCEPROP 1 LAST COMMENT_BODY TRUE
J 0
(-570 4755);
DISPLAY 0.872340 (-570 4755);
PAINT GREEN (-570 4755);
DISPLAY INVISIBLE (-570 4755);
FORCEPROP 2 LAST PATH I105
J 0
(-225 4900);
DISPLAY 0.680851 (-225 4900);
DISPLAY INVISIBLE (-225 4900);
FORCEADD Q_RES..1
(-1625 4925);
FORCEPROP 1 LAST LOCATION R495
J 0
(-1975 4925);
DISPLAY 0.489362 (-1975 4925);
PAINT SKYBLUE (-1975 4925);
FORCEPROP 2 LAST $SEC 1
J 0
(-1675 5125);
DISPLAY 0.680851 (-1675 5125);
PAINT MONO (-1675 5125);
DISPLAY INVISIBLE (-1675 5125);
FORCEPROP 2 LAST CDS_SEC 1
J 0
(-1675 5125);
DISPLAY 0.680851 (-1675 5125);
DISPLAY INVISIBLE (-1675 5125);
FORCEPROP 1 LASTPIN (-1725 4925) $PN 1
J 0
(-1713 4937);
DISPLAY 0.489362 (-1713 4937);
PAINT MONO (-1713 4937);
FORCEPROP 1 LASTPIN (-1525 4925) $PN 2
J 0
(-1563 4937);
DISPLAY 0.489362 (-1563 4937);
PAINT MONO (-1563 4937);
FORCEPROP 1 LAST VALUE 4.7K
J 0
(-1500 4925);
DISPLAY 0.489362 (-1500 4925);
PAINT SKYBLUE (-1500 4925);
FORCEPROP 2 LAST CDS_LIB pure_quanta
J 0
(-1625 4925);
DISPLAY INVISIBLE (-1625 4925);
FORCEPROP 1 LAST PATH I106
J 0
(-1675 5075);
DISPLAY 0.978723 (-1675 5075);
PAINT WHITE (-1675 5075);
DISPLAY INVISIBLE (-1675 5075);
FORCEPROP 1 LAST WATTAGE 1/16W
J 2
(-1650 4775);
DISPLAY 0.510638 (-1650 4775);
PAINT SKYBLUE (-1650 4775);
DISPLAY INVISIBLE (-1650 4775);
FORCEPROP 1 LAST MATERIAL CHIP
J 0
(-1525 4900);
DISPLAY 0.489362 (-1525 4900);
PAINT SKYBLUE (-1525 4900);
DISPLAY INVISIBLE (-1525 4900);
FORCEPROP 1 LAST TOLERANCE 5%
J 0
(-1500 4925);
DISPLAY 0.510638 (-1500 4925);
PAINT SKYBLUE (-1500 4925);
DISPLAY INVISIBLE (-1500 4925);
FORCEPROP 1 LAST PART_NUMBER TMP_QCS24702JB38
J 0
(-1675 5025);
DISPLAY 0.510638 (-1675 5025);
PAINT SKYBLUE (-1675 5025);
DISPLAY INVISIBLE (-1675 5025);
FORCEPROP 1 LAST PACK_TYPE 0402LF
J 0
(-1375 4775);
DISPLAY 0.510638 (-1375 4775);
PAINT SKYBLUE (-1375 4775);
DISPLAY INVISIBLE (-1375 4775);
FORCEADD Q_RES..1
(-1625 4850);
FORCEPROP 1 LAST LOCATION R498
J 0
(-1975 4850);
DISPLAY 0.489362 (-1975 4850);
PAINT SKYBLUE (-1975 4850);
FORCEPROP 2 LAST $SEC 1
J 0
(-1675 5050);
DISPLAY 0.680851 (-1675 5050);
PAINT MONO (-1675 5050);
DISPLAY INVISIBLE (-1675 5050);
FORCEPROP 2 LAST CDS_SEC 1
J 0
(-1675 5050);
DISPLAY 0.680851 (-1675 5050);
DISPLAY INVISIBLE (-1675 5050);
FORCEPROP 1 LASTPIN (-1725 4850) $PN 1
J 0
(-1713 4862);
DISPLAY 0.489362 (-1713 4862);
PAINT MONO (-1713 4862);
FORCEPROP 1 LASTPIN (-1525 4850) $PN 2
J 0
(-1563 4862);
DISPLAY 0.489362 (-1563 4862);
PAINT MONO (-1563 4862);
FORCEPROP 1 LAST VALUE 4.7K
J 0
(-1500 4850);
DISPLAY 0.489362 (-1500 4850);
PAINT SKYBLUE (-1500 4850);
FORCEPROP 2 LAST CDS_LIB pure_quanta
J 0
(-1625 4850);
DISPLAY INVISIBLE (-1625 4850);
FORCEPROP 1 LAST PATH I107
J 0
(-1675 5000);
DISPLAY 0.978723 (-1675 5000);
PAINT WHITE (-1675 5000);
DISPLAY INVISIBLE (-1675 5000);
FORCEPROP 1 LAST WATTAGE 1/16W
J 2
(-1650 4700);
DISPLAY 0.510638 (-1650 4700);
PAINT SKYBLUE (-1650 4700);
DISPLAY INVISIBLE (-1650 4700);
FORCEPROP 1 LAST MATERIAL CHIP
J 0
(-1525 4825);
DISPLAY 0.489362 (-1525 4825);
PAINT SKYBLUE (-1525 4825);
DISPLAY INVISIBLE (-1525 4825);
FORCEPROP 1 LAST TOLERANCE 5%
J 0
(-1500 4850);
DISPLAY 0.510638 (-1500 4850);
PAINT SKYBLUE (-1500 4850);
DISPLAY INVISIBLE (-1500 4850);
FORCEPROP 1 LAST PART_NUMBER TMP_QCS24702JB38
J 0
(-1675 4950);
DISPLAY 0.510638 (-1675 4950);
PAINT SKYBLUE (-1675 4950);
DISPLAY INVISIBLE (-1675 4950);
FORCEPROP 1 LAST PACK_TYPE 0402LF
J 0
(-1375 4700);
DISPLAY 0.510638 (-1375 4700);
PAINT SKYBLUE (-1375 4700);
DISPLAY INVISIBLE (-1375 4700);
FORCEADD UNIVERSAL_POWER..1
R 2
(-2025 5400);
FORCEPROP 3 LASTPIN (-2025 5350) SIG_NAME PVDD18_S5_P0\g
J 0
(-2015 5360);
DISPLAY 0.659574 (-2015 5360);
PAINT MONO (-2015 5360);
DISPLAY INVISIBLE (-2015 5360);
FORCEPROP 1 LAST HDL_POWER PVDD18_S5_P0
J 1
(-2025 5450);
DISPLAY 0.489362 (-2025 5450);
PAINT GREEN (-2025 5450);
FORCEPROP 2 LAST CDS_LIB pure_quanta_power
J 0
(-2025 5400);
DISPLAY INVISIBLE (-2025 5400);
FORCEPROP 1 LAST PATH I108
J 2
(-2075 5425);
DISPLAY 0.872340 (-2075 5425);
PAINT AQUA (-2075 5425);
DISPLAY INVISIBLE (-2075 5425);
FORCEADD OFFPAGE..2
(-525 5200);
FORCEPROP 2 LAST $XR1 28 
J 0
(-246 5200);
DISPLAY 0.638298 (-246 5200);
PAINT MONO (-246 5200);
FORCEPROP 2 LAST $XR0 34 
J 0
(-336 5200);
DISPLAY 0.638298 (-336 5200);
PAINT MONO (-336 5200);
FORCEPROP 2 LAST CDS_LIB standard
J 0
(-525 5200);
DISPLAY INVISIBLE (-525 5200);
FORCEPROP 1 LAST OFFPAGE TRUE
J 0
(-200 5075);
DISPLAY 0.872340 (-200 5075);
PAINT GREEN (-200 5075);
DISPLAY INVISIBLE (-200 5075);
FORCEPROP 1 LAST COMMENT_BODY TRUE
J 0
(-570 5105);
DISPLAY 0.872340 (-570 5105);
PAINT GREEN (-570 5105);
DISPLAY INVISIBLE (-570 5105);
FORCEPROP 2 LAST PATH I109
J 0
(-225 5250);
DISPLAY 0.680851 (-225 5250);
DISPLAY INVISIBLE (-225 5250);
FORCEADD OFFPAGE..2
(-525 5100);
FORCEPROP 2 LAST $XR1 28 
J 0
(-246 5100);
DISPLAY 0.638298 (-246 5100);
PAINT MONO (-246 5100);
FORCEPROP 2 LAST $XR0 34 
J 0
(-336 5100);
DISPLAY 0.638298 (-336 5100);
PAINT MONO (-336 5100);
FORCEPROP 2 LAST CDS_LIB standard
J 0
(-525 5100);
DISPLAY INVISIBLE (-525 5100);
FORCEPROP 1 LAST OFFPAGE TRUE
J 0
(-200 4975);
DISPLAY 0.872340 (-200 4975);
PAINT GREEN (-200 4975);
DISPLAY INVISIBLE (-200 4975);
FORCEPROP 1 LAST COMMENT_BODY TRUE
J 0
(-570 5005);
DISPLAY 0.872340 (-570 5005);
PAINT GREEN (-570 5005);
DISPLAY INVISIBLE (-570 5005);
FORCEPROP 2 LAST PATH I110
J 0
(-225 5150);
DISPLAY 0.680851 (-225 5150);
DISPLAY INVISIBLE (-225 5150);
FORCEADD Q_RES..1
(-1625 5200);
FORCEPROP 1 LAST LOCATION R650
J 0
(-1975 5200);
DISPLAY 0.489362 (-1975 5200);
PAINT SKYBLUE (-1975 5200);
FORCEPROP 2 LAST $SEC 1
J 0
(-1675 5400);
DISPLAY 0.680851 (-1675 5400);
PAINT MONO (-1675 5400);
DISPLAY INVISIBLE (-1675 5400);
FORCEPROP 2 LAST CDS_SEC 1
J 0
(-1675 5400);
DISPLAY 0.680851 (-1675 5400);
DISPLAY INVISIBLE (-1675 5400);
FORCEPROP 1 LASTPIN (-1725 5200) $PN 1
J 0
(-1713 5212);
DISPLAY 0.489362 (-1713 5212);
PAINT MONO (-1713 5212);
FORCEPROP 1 LASTPIN (-1525 5200) $PN 2
J 0
(-1563 5212);
DISPLAY 0.489362 (-1563 5212);
PAINT MONO (-1563 5212);
FORCEPROP 1 LAST VALUE 4.7K
J 0
(-1500 5200);
DISPLAY 0.489362 (-1500 5200);
PAINT SKYBLUE (-1500 5200);
FORCEPROP 2 LAST CDS_LIB pure_quanta
J 0
(-1625 5200);
DISPLAY INVISIBLE (-1625 5200);
FORCEPROP 1 LAST PATH I111
J 0
(-1675 5350);
DISPLAY 0.978723 (-1675 5350);
PAINT WHITE (-1675 5350);
DISPLAY INVISIBLE (-1675 5350);
FORCEPROP 1 LAST WATTAGE 1/16W
J 2
(-1650 5050);
DISPLAY 0.510638 (-1650 5050);
PAINT SKYBLUE (-1650 5050);
DISPLAY INVISIBLE (-1650 5050);
FORCEPROP 1 LAST MATERIAL CHIP
J 0
(-1525 5175);
DISPLAY 0.489362 (-1525 5175);
PAINT SKYBLUE (-1525 5175);
DISPLAY INVISIBLE (-1525 5175);
FORCEPROP 1 LAST TOLERANCE 5%
J 0
(-1500 5200);
DISPLAY 0.510638 (-1500 5200);
PAINT SKYBLUE (-1500 5200);
DISPLAY INVISIBLE (-1500 5200);
FORCEPROP 1 LAST PART_NUMBER TMP_QCS24702JB38
J 0
(-1675 5300);
DISPLAY 0.510638 (-1675 5300);
PAINT SKYBLUE (-1675 5300);
DISPLAY INVISIBLE (-1675 5300);
FORCEPROP 1 LAST PACK_TYPE 0402LF
J 0
(-1375 5050);
DISPLAY 0.510638 (-1375 5050);
PAINT SKYBLUE (-1375 5050);
DISPLAY INVISIBLE (-1375 5050);
FORCEADD Q_RES..1
(-1625 5100);
FORCEPROP 1 LAST LOCATION R651
J 0
(-1975 5100);
DISPLAY 0.489362 (-1975 5100);
PAINT SKYBLUE (-1975 5100);
FORCEPROP 2 LAST $SEC 1
J 0
(-1675 5300);
DISPLAY 0.680851 (-1675 5300);
PAINT MONO (-1675 5300);
DISPLAY INVISIBLE (-1675 5300);
FORCEPROP 2 LAST CDS_SEC 1
J 0
(-1675 5300);
DISPLAY 0.680851 (-1675 5300);
DISPLAY INVISIBLE (-1675 5300);
FORCEPROP 1 LASTPIN (-1725 5100) $PN 1
J 0
(-1713 5112);
DISPLAY 0.489362 (-1713 5112);
PAINT MONO (-1713 5112);
FORCEPROP 1 LASTPIN (-1525 5100) $PN 2
J 0
(-1563 5112);
DISPLAY 0.489362 (-1563 5112);
PAINT MONO (-1563 5112);
FORCEPROP 1 LAST VALUE 4.7K
J 0
(-1500 5100);
DISPLAY 0.489362 (-1500 5100);
PAINT SKYBLUE (-1500 5100);
FORCEPROP 2 LAST CDS_LIB pure_quanta
J 0
(-1625 5100);
DISPLAY INVISIBLE (-1625 5100);
FORCEPROP 1 LAST PATH I112
J 0
(-1675 5250);
DISPLAY 0.978723 (-1675 5250);
PAINT WHITE (-1675 5250);
DISPLAY INVISIBLE (-1675 5250);
FORCEPROP 1 LAST WATTAGE 1/16W
J 2
(-1650 4950);
DISPLAY 0.510638 (-1650 4950);
PAINT SKYBLUE (-1650 4950);
DISPLAY INVISIBLE (-1650 4950);
FORCEPROP 1 LAST MATERIAL CHIP
J 0
(-1525 5075);
DISPLAY 0.489362 (-1525 5075);
PAINT SKYBLUE (-1525 5075);
DISPLAY INVISIBLE (-1525 5075);
FORCEPROP 1 LAST TOLERANCE 5%
J 0
(-1500 5100);
DISPLAY 0.510638 (-1500 5100);
PAINT SKYBLUE (-1500 5100);
DISPLAY INVISIBLE (-1500 5100);
FORCEPROP 1 LAST PART_NUMBER TMP_QCS24702JB38
J 0
(-1675 5200);
DISPLAY 0.510638 (-1675 5200);
PAINT SKYBLUE (-1675 5200);
DISPLAY INVISIBLE (-1675 5200);
FORCEPROP 1 LAST PACK_TYPE 0402LF
J 0
(-1375 4950);
DISPLAY 0.510638 (-1375 4950);
PAINT SKYBLUE (-1375 4950);
DISPLAY INVISIBLE (-1375 4950);
FORCEADD PCA9617ADP..1
(-7200 5575);
FORCEPROP 1 LAST LOCATION U27
J 0
(-7474 5985);
DISPLAY 0.489362 (-7474 5985);
PAINT SKYBLUE (-7474 5985);
FORCEPROP 0 LAST $SEC 1
J 0
(-7425 6125);
DISPLAY 0.680851 (-7425 6125);
PAINT MONO (-7425 6125);
DISPLAY INVISIBLE (-7425 6125);
FORCEPROP 0 LAST CDS_SEC 1
J 0
(-7425 6125);
DISPLAY 1.021277 (-7425 6125);
DISPLAY INVISIBLE (-7425 6125);
FORCEPROP 0 LASTPIN (-6775 5375) $PN 5
J 0
(-6765 5385);
DISPLAY 0.489362 (-6765 5385);
PAINT MONO (-6765 5385);
FORCEPROP 0 LASTPIN (-7625 5375) $PN 4
J 2
(-7635 5385);
DISPLAY 0.489362 (-7635 5385);
PAINT MONO (-7635 5385);
FORCEPROP 0 LASTPIN (-7625 5625) $PN 2
J 2
(-7635 5635);
DISPLAY 0.489362 (-7635 5635);
PAINT MONO (-7635 5635);
FORCEPROP 0 LASTPIN (-6775 5625) $PN 7
J 0
(-6765 5635);
DISPLAY 0.489362 (-6765 5635);
PAINT MONO (-6765 5635);
FORCEPROP 0 LASTPIN (-7625 5525) $PN 3
J 2
(-7635 5535);
DISPLAY 0.489362 (-7635 5535);
PAINT MONO (-7635 5535);
FORCEPROP 0 LASTPIN (-6775 5525) $PN 6
J 0
(-6765 5535);
DISPLAY 0.489362 (-6765 5535);
PAINT MONO (-6765 5535);
FORCEPROP 0 LASTPIN (-7625 5775) $PN 1
J 2
(-7635 5785);
DISPLAY 0.489362 (-7635 5785);
PAINT MONO (-7635 5785);
FORCEPROP 0 LASTPIN (-6775 5775) $PN 8
J 0
(-6765 5785);
DISPLAY 0.489362 (-6765 5785);
PAINT MONO (-6765 5785);
FORCEPROP 2 LAST PART_TYPE SMLF
J 0
(-7425 6075);
DISPLAY 1.021277 (-7425 6075);
FORCEPROP 1 LAST MATERIAL IC
J 0
(-7474 5880);
DISPLAY 0.489362 (-7474 5880);
PAINT SKYBLUE (-7474 5880);
FORCEPROP 2 LAST VALUE PCA9617ADP
J 0
(-7425 6025);
DISPLAY 0.489362 (-7425 6025);
PAINT SKYBLUE (-7425 6025);
FORCEPROP 1 LAST PART_NUMBER AL009617K02
J 0
(-7474 5935);
DISPLAY 0.489362 (-7474 5935);
PAINT SKYBLUE (-7474 5935);
FORCEPROP 1 LAST NEEDS_NO_SIZE TRUE
J 0
(-6925 5275);
DISPLAY 0.468085 (-6925 5275);
PAINT GREEN (-6925 5275);
DISPLAY INVISIBLE (-6925 5275);
FORCEPROP 1 LAST CDS_LMAN_SYM_OUTLINE -275,300,275,-300
J 0
(-7200 5575);
DISPLAY 0.468085 (-7200 5575);
PAINT GREEN (-7200 5575);
DISPLAY INVISIBLE (-7200 5575);
FORCEPROP 2 LAST CDS_LIB pure_quanta
J 0
(-7200 5575);
DISPLAY INVISIBLE (-7200 5575);
FORCEPROP 1 LAST PATH I18
J 0
(-7200 5575);
DISPLAY 0.723404 (-7200 5575);
PAINT GREEN (-7200 5575);
DISPLAY INVISIBLE (-7200 5575);
FORCEADD OFFPAGE..2
(-600 6000);
FORCEPROP 2 LAST $XR1 79 
J 0
(-321 6000);
DISPLAY 0.638298 (-321 6000);
PAINT MONO (-321 6000);
FORCEPROP 2 LAST $XR0 34 
J 0
(-411 6000);
DISPLAY 0.638298 (-411 6000);
PAINT MONO (-411 6000);
FORCEPROP 2 LAST CDS_LIB standard
J 0
(-600 6000);
DISPLAY INVISIBLE (-600 6000);
FORCEPROP 1 LAST OFFPAGE TRUE
J 0
(-275 5875);
DISPLAY 0.872340 (-275 5875);
PAINT GREEN (-275 5875);
DISPLAY INVISIBLE (-275 5875);
FORCEPROP 1 LAST COMMENT_BODY TRUE
J 0
(-645 5905);
DISPLAY 0.872340 (-645 5905);
PAINT GREEN (-645 5905);
DISPLAY INVISIBLE (-645 5905);
FORCEPROP 2 LAST PATH I2
J 0
(-300 6050);
DISPLAY 0.680851 (-300 6050);
DISPLAY INVISIBLE (-300 6050);
FORCEADD OFFPAGE..5
R 2
(-6025 4175);
FORCEPROP 2 LAST $XR1 28 
J 0
(-5746 4175);
DISPLAY 0.638298 (-5746 4175);
PAINT MONO (-5746 4175);
FORCEPROP 2 LAST $XR0 34 
J 0
(-5836 4175);
DISPLAY 0.638298 (-5836 4175);
PAINT MONO (-5836 4175);
FORCEPROP 2 LAST CDS_LIB standard
J 0
(-6025 4175);
DISPLAY INVISIBLE (-6025 4175);
FORCEPROP 2 LAST BOM_COST SYS_CLOCK
J 2
(-6225 4275);
DISPLAY 0.808511 (-6225 4275);
DISPLAY INVISIBLE (-6225 4275);
FORCEPROP 1 LAST OFFPAGE TRUE
J 2
(-6350 4050);
DISPLAY 0.872340 (-6350 4050);
PAINT GREEN (-6350 4050);
DISPLAY INVISIBLE (-6350 4050);
FORCEPROP 1 LAST COMMENT_BODY TRUE
J 2
(-6125 4100);
DISPLAY 0.872340 (-6125 4100);
PAINT GREEN (-6125 4100);
DISPLAY INVISIBLE (-6125 4100);
FORCEPROP 2 LAST PATH I26
J 0
(-5725 4225);
DISPLAY 0.680851 (-5725 4225);
DISPLAY INVISIBLE (-5725 4225);
FORCEPROP 2 LAST ROOM DB2000_2_NVME
J 2
(-6225 4225);
DISPLAY 0.808511 (-6225 4225);
PAINT RED (-6225 4225);
DISPLAY INVISIBLE (-6225 4225);
FORCEADD OFFPAGE..5
R 2
(-6025 4075);
FORCEPROP 2 LAST $XR1 28 
J 0
(-5746 4075);
DISPLAY 0.638298 (-5746 4075);
PAINT MONO (-5746 4075);
FORCEPROP 2 LAST $XR0 34 
J 0
(-5836 4075);
DISPLAY 0.638298 (-5836 4075);
PAINT MONO (-5836 4075);
FORCEPROP 2 LAST CDS_LIB standard
J 0
(-6025 4075);
DISPLAY INVISIBLE (-6025 4075);
FORCEPROP 2 LAST BOM_COST SYS_CLOCK
J 2
(-6225 4175);
DISPLAY 0.808511 (-6225 4175);
DISPLAY INVISIBLE (-6225 4175);
FORCEPROP 1 LAST OFFPAGE TRUE
J 2
(-6350 3950);
DISPLAY 0.872340 (-6350 3950);
PAINT GREEN (-6350 3950);
DISPLAY INVISIBLE (-6350 3950);
FORCEPROP 1 LAST COMMENT_BODY TRUE
J 2
(-6125 4000);
DISPLAY 0.872340 (-6125 4000);
PAINT GREEN (-6125 4000);
DISPLAY INVISIBLE (-6125 4000);
FORCEPROP 2 LAST PATH I27
J 0
(-5725 4125);
DISPLAY 0.680851 (-5725 4125);
DISPLAY INVISIBLE (-5725 4125);
FORCEPROP 2 LAST ROOM DB2000_2_NVME
J 2
(-6225 4125);
DISPLAY 0.808511 (-6225 4125);
PAINT RED (-6225 4125);
DISPLAY INVISIBLE (-6225 4125);
FORCEADD UNIVERSAL_GND..1
(-6750 4225);
FORCEPROP 3 LASTPIN (-6750 4275) SIG_NAME GND\g
J 0
(-6740 4285);
DISPLAY 0.659574 (-6740 4285);
PAINT MONO (-6740 4285);
DISPLAY INVISIBLE (-6740 4285);
FORCEPROP 2 LAST CDS_LIB pure_quanta_power
J 0
(-6750 4225);
DISPLAY INVISIBLE (-6750 4225);
FORCEPROP 1 LAST PATH I28
J 0
(-6675 4225);
DISPLAY 0.872340 (-6675 4225);
PAINT AQUA (-6675 4225);
DISPLAY INVISIBLE (-6675 4225);
FORCEPROP 1 LAST HDL_POWER GND
J 1
(-6725 4150);
DISPLAY 0.872340 (-6725 4150);
PAINT GREEN (-6725 4150);
DISPLAY INVISIBLE (-6725 4150);
FORCEADD Q_CAP..1
(-6750 4425);
FORCEPROP 1 LAST LOCATION C225
J 0
(-6700 4575);
DISPLAY 0.489362 (-6700 4575);
PAINT SKYBLUE (-6700 4575);
FORCEPROP 2 LAST $SEC 1
J 0
(-6700 4625);
DISPLAY 0.680851 (-6700 4625);
PAINT MONO (-6700 4625);
DISPLAY INVISIBLE (-6700 4625);
FORCEPROP 2 LAST CDS_SEC 1
J 0
(-6700 4625);
DISPLAY 0.680851 (-6700 4625);
DISPLAY INVISIBLE (-6700 4625);
FORCEPROP 1 LASTPIN (-6750 4525) $PN 1
J 0
(-6740 4505);
DISPLAY 0.489362 (-6740 4505);
PAINT MONO (-6740 4505);
FORCEPROP 1 LASTPIN (-6750 4325) $PN 2
J 0
(-6740 4305);
DISPLAY 0.489362 (-6740 4305);
PAINT MONO (-6740 4305);
FORCEPROP 1 LAST MATERIAL X7R
J 0
(-6700 4375);
DISPLAY 0.489362 (-6700 4375);
PAINT SKYBLUE (-6700 4375);
FORCEPROP 1 LAST TOLERANCE 10%
J 0
(-6700 4425);
DISPLAY 0.489362 (-6700 4425);
PAINT SKYBLUE (-6700 4425);
FORCEPROP 1 LAST VALUE 0.1UF
J 0
(-6700 4525);
DISPLAY 0.489362 (-6700 4525);
PAINT SKYBLUE (-6700 4525);
FORCEPROP 1 LAST VOLTAGE 25V
J 0
(-6700 4475);
DISPLAY 0.489362 (-6700 4475);
PAINT SKYBLUE (-6700 4475);
FORCEPROP 1 LAST PACK_TYPE 0402
J 0
(-6700 4325);
DISPLAY 0.489362 (-6700 4325);
PAINT SKYBLUE (-6700 4325);
FORCEPROP 2 LAST CDS_LIB pure_quanta
J 0
(-6750 4425);
DISPLAY INVISIBLE (-6750 4425);
FORCEPROP 1 LAST PATH I29
J 0
(-6700 4575);
DISPLAY 0.978723 (-6700 4575);
PAINT WHITE (-6700 4575);
DISPLAY INVISIBLE (-6700 4575);
FORCEPROP 1 LAST PART_NUMBER CH4104K1B00
J 0
(-6700 4275);
DISPLAY 0.489362 (-6700 4275);
PAINT SKYBLUE (-6700 4275);
DISPLAY INVISIBLE (-6700 4275);
FORCEADD UNIVERSAL_POWER..1
R 2
(-2025 6475);
FORCEPROP 3 LASTPIN (-2025 6425) SIG_NAME P3V3_STBY\g
J 0
(-2015 6435);
DISPLAY 0.659574 (-2015 6435);
PAINT MONO (-2015 6435);
DISPLAY INVISIBLE (-2015 6435);
FORCEPROP 1 LAST HDL_POWER P3V3_STBY
J 1
(-2025 6525);
DISPLAY 0.489362 (-2025 6525);
PAINT GREEN (-2025 6525);
FORCEPROP 2 LAST CDS_LIB pure_quanta_power
J 0
(-2025 6475);
DISPLAY INVISIBLE (-2025 6475);
FORCEPROP 1 LAST PATH I3
J 2
(-2075 6500);
DISPLAY 0.872340 (-2075 6500);
PAINT AQUA (-2075 6500);
DISPLAY INVISIBLE (-2075 6500);
FORCEADD UNIVERSAL_POWER..1
R 2
(-6825 4750);
FORCEPROP 3 LASTPIN (-6825 4700) SIG_NAME P3V3_STBY\g
J 0
(-6815 4710);
DISPLAY 0.659574 (-6815 4710);
PAINT MONO (-6815 4710);
DISPLAY INVISIBLE (-6815 4710);
FORCEPROP 1 LAST HDL_POWER P3V3_STBY
J 1
(-6825 4800);
DISPLAY 0.489362 (-6825 4800);
PAINT GREEN (-6825 4800);
FORCEPROP 2 LAST CDS_LIB pure_quanta_power
J 0
(-6825 4750);
DISPLAY INVISIBLE (-6825 4750);
FORCEPROP 1 LAST PATH I31
J 2
(-6875 4775);
DISPLAY 0.872340 (-6875 4775);
PAINT AQUA (-6875 4775);
DISPLAY INVISIBLE (-6875 4775);
FORCEADD SN74LVC2G07DCKR..1
(-7300 4125);
FORCEPROP 1 LAST LOCATION U11
J 0
(-7475 4330);
DISPLAY 0.489362 (-7475 4330);
PAINT SKYBLUE (-7475 4330);
FORCEPROP 2 LAST $SEC 1
J 0
(-7475 4475);
DISPLAY 0.680851 (-7475 4475);
PAINT MONO (-7475 4475);
DISPLAY INVISIBLE (-7475 4475);
FORCEPROP 2 LAST CDS_SEC 1
J 0
(-7475 4475);
DISPLAY 0.680851 (-7475 4475);
DISPLAY INVISIBLE (-7475 4475);
FORCEPROP 2 LASTPIN (-7625 4175) $PN 1
J 2
(-7635 4185);
DISPLAY 0.489362 (-7635 4185);
PAINT MONO (-7635 4185);
FORCEPROP 2 LASTPIN (-6975 4175) $PN 6
J 0
(-6965 4185);
DISPLAY 0.489362 (-6965 4185);
PAINT MONO (-6965 4185);
FORCEPROP 2 LASTPIN (-7625 4075) $PN 3
J 2
(-7635 4085);
DISPLAY 0.489362 (-7635 4085);
PAINT MONO (-7635 4085);
FORCEPROP 2 LASTPIN (-6975 4075) $PN 4
J 0
(-6965 4085);
DISPLAY 0.489362 (-6965 4085);
PAINT MONO (-6965 4085);
FORCEPROP 2 LASTPIN (-7625 4125) $PN 2
J 2
(-7635 4135);
DISPLAY 0.489362 (-7635 4135);
PAINT MONO (-7635 4135);
FORCEPROP 2 LASTPIN (-6975 4125) $PN 5
J 0
(-6965 4135);
DISPLAY 0.489362 (-6965 4135);
PAINT MONO (-6965 4135);
FORCEPROP 1 LAST MATERIAL IC
J 0
(-7475 4235);
DISPLAY 0.489362 (-7475 4235);
PAINT SKYBLUE (-7475 4235);
FORCEPROP 2 LAST VALUE SN74LVC2G07DCKR
J 0
(-7475 4425);
DISPLAY 0.489362 (-7475 4425);
PAINT SKYBLUE (-7475 4425);
FORCEPROP 1 LAST PART_NUMBER AL002G07006
J 0
(-7475 4285);
DISPLAY 0.489362 (-7475 4285);
PAINT SKYBLUE (-7475 4285);
FORCEPROP 2 LAST PACK_TYPE SMLF
J 0
(-7475 4375);
DISPLAY 0.489362 (-7475 4375);
PAINT SKYBLUE (-7475 4375);
FORCEPROP 2 LAST CDS_LIB pure_quanta
J 0
(-7300 4125);
DISPLAY INVISIBLE (-7300 4125);
FORCEPROP 1 LAST NEEDS_NO_SIZE TRUE
J 0
(-7300 4125);
DISPLAY 0.468085 (-7300 4125);
PAINT GREEN (-7300 4125);
DISPLAY INVISIBLE (-7300 4125);
FORCEPROP 1 LAST PATH I32
J 0
(-7150 4230);
DISPLAY 0.723404 (-7150 4230);
PAINT GREEN (-7150 4230);
DISPLAY INVISIBLE (-7150 4230);
FORCEADD UNIVERSAL_GND..1
R 5
(-7725 4125);
FORCEPROP 3 LASTPIN (-7675 4125) SIG_NAME GND\g
J 0
(-7665 4135);
DISPLAY 0.659574 (-7665 4135);
PAINT MONO (-7665 4135);
DISPLAY INVISIBLE (-7665 4135);
FORCEPROP 2 LAST CDS_LIB pure_quanta_power
R 3
J 0
(-7725 4125);
DISPLAY INVISIBLE (-7725 4125);
FORCEPROP 1 LAST PATH I33
R 3
J 0
(-7725 4050);
DISPLAY 0.872340 (-7725 4050);
PAINT AQUA (-7725 4050);
DISPLAY INVISIBLE (-7725 4050);
FORCEPROP 1 LAST HDL_POWER GND
R 3
J 1
(-7800 4100);
DISPLAY 0.872340 (-7800 4100);
PAINT GREEN (-7800 4100);
DISPLAY INVISIBLE (-7800 4100);
FORCEADD OFFPAGE..4
R 2
(-8575 4175);
FORCEPROP 2 LAST $XR1 81 
J 0
(-8917 4175);
DISPLAY 0.638298 (-8917 4175);
PAINT MONO (-8917 4175);
FORCEPROP 2 LAST $XR0 114 
J 0
(-8827 4175);
DISPLAY 0.638298 (-8827 4175);
PAINT MONO (-8827 4175);
FORCEPROP 2 LAST CDS_LIB standard
J 0
(-8575 4175);
DISPLAY INVISIBLE (-8575 4175);
FORCEPROP 1 LAST OFFPAGE TRUE
J 2
(-8900 4050);
DISPLAY 0.872340 (-8900 4050);
PAINT GREEN (-8900 4050);
DISPLAY INVISIBLE (-8900 4050);
FORCEPROP 1 LAST COMMENT_BODY TRUE
J 2
(-8550 4075);
DISPLAY 0.872340 (-8550 4075);
PAINT GREEN (-8550 4075);
DISPLAY INVISIBLE (-8550 4075);
FORCEPROP 2 LAST PATH I34
J 0
(-8850 4225);
DISPLAY 0.680851 (-8850 4225);
DISPLAY INVISIBLE (-8850 4225);
FORCEADD OFFPAGE..4
R 2
(-8575 4075);
FORCEPROP 2 LAST $XR1 81 
J 0
(-8917 4075);
DISPLAY 0.638298 (-8917 4075);
PAINT MONO (-8917 4075);
FORCEPROP 2 LAST $XR0 114 
J 0
(-8827 4075);
DISPLAY 0.638298 (-8827 4075);
PAINT MONO (-8827 4075);
FORCEPROP 2 LAST CDS_LIB standard
J 0
(-8575 4075);
DISPLAY INVISIBLE (-8575 4075);
FORCEPROP 1 LAST OFFPAGE TRUE
J 2
(-8900 3950);
DISPLAY 0.872340 (-8900 3950);
PAINT GREEN (-8900 3950);
DISPLAY INVISIBLE (-8900 3950);
FORCEPROP 1 LAST COMMENT_BODY TRUE
J 2
(-8550 3975);
DISPLAY 0.872340 (-8550 3975);
PAINT GREEN (-8550 3975);
DISPLAY INVISIBLE (-8550 3975);
FORCEPROP 2 LAST PATH I35
J 0
(-8850 4125);
DISPLAY 0.680851 (-8850 4125);
DISPLAY INVISIBLE (-8850 4125);
FORCEADD Q_RES..1
(-1675 6000);
FORCEPROP 1 LAST LOCATION R499
J 0
(-1925 6000);
DISPLAY 0.489362 (-1925 6000);
PAINT SKYBLUE (-1925 6000);
FORCEPROP 2 LAST $SEC 1
J 0
(-1725 6200);
DISPLAY 0.680851 (-1725 6200);
PAINT MONO (-1725 6200);
DISPLAY INVISIBLE (-1725 6200);
FORCEPROP 2 LAST CDS_SEC 1
J 0
(-1725 6200);
DISPLAY 0.680851 (-1725 6200);
DISPLAY INVISIBLE (-1725 6200);
FORCEPROP 1 LASTPIN (-1775 6000) $PN 1
J 0
(-1763 6012);
DISPLAY 0.489362 (-1763 6012);
PAINT MONO (-1763 6012);
FORCEPROP 1 LASTPIN (-1575 6000) $PN 2
J 0
(-1613 6012);
DISPLAY 0.489362 (-1613 6012);
PAINT MONO (-1613 6012);
FORCEPROP 1 LAST VALUE 4.7K
J 0
(-1550 6000);
DISPLAY 0.489362 (-1550 6000);
PAINT SKYBLUE (-1550 6000);
FORCEPROP 2 LAST CDS_LIB pure_quanta
J 0
(-1675 6000);
DISPLAY INVISIBLE (-1675 6000);
FORCEPROP 1 LAST PATH I4
J 0
(-1725 6150);
DISPLAY 0.978723 (-1725 6150);
PAINT WHITE (-1725 6150);
DISPLAY INVISIBLE (-1725 6150);
FORCEPROP 1 LAST WATTAGE 1/16W
J 2
(-1700 5850);
DISPLAY 0.510638 (-1700 5850);
PAINT SKYBLUE (-1700 5850);
DISPLAY INVISIBLE (-1700 5850);
FORCEPROP 1 LAST MATERIAL CHIP
J 0
(-1575 5975);
DISPLAY 0.489362 (-1575 5975);
PAINT SKYBLUE (-1575 5975);
DISPLAY INVISIBLE (-1575 5975);
FORCEPROP 1 LAST TOLERANCE 5%
J 0
(-1550 6000);
DISPLAY 0.510638 (-1550 6000);
PAINT SKYBLUE (-1550 6000);
DISPLAY INVISIBLE (-1550 6000);
FORCEPROP 1 LAST PART_NUMBER TMP_QCS24702JB38
J 0
(-1725 6100);
DISPLAY 0.510638 (-1725 6100);
PAINT SKYBLUE (-1725 6100);
DISPLAY INVISIBLE (-1725 6100);
FORCEPROP 1 LAST PACK_TYPE 0402LF
J 0
(-1425 5850);
DISPLAY 0.510638 (-1425 5850);
PAINT SKYBLUE (-1425 5850);
DISPLAY INVISIBLE (-1425 5850);
FORCEADD UNIVERSAL_GND..1
(-7775 5175);
FORCEPROP 3 LASTPIN (-7775 5225) SIG_NAME GND\g
J 0
(-7765 5235);
DISPLAY 0.659574 (-7765 5235);
PAINT MONO (-7765 5235);
DISPLAY INVISIBLE (-7765 5235);
FORCEPROP 2 LAST CDS_LIB pure_quanta_power
J 0
(-7775 5175);
DISPLAY INVISIBLE (-7775 5175);
FORCEPROP 1 LAST PATH I40
J 0
(-7700 5175);
DISPLAY 0.872340 (-7700 5175);
PAINT AQUA (-7700 5175);
DISPLAY INVISIBLE (-7700 5175);
FORCEPROP 1 LAST HDL_POWER GND
J 1
(-7750 5100);
DISPLAY 0.872340 (-7750 5100);
PAINT GREEN (-7750 5100);
DISPLAY INVISIBLE (-7750 5100);
FORCEADD OFFPAGE..1
(-8575 5625);
FORCEPROP 2 LAST $XR1 34 
J 0
(-8916 5625);
DISPLAY 0.638298 (-8916 5625);
PAINT MONO (-8916 5625);
FORCEPROP 2 LAST $XR0 28 
J 0
(-8826 5625);
DISPLAY 0.638298 (-8826 5625);
PAINT MONO (-8826 5625);
FORCEPROP 2 LAST CDS_LIB standard
J 0
(-8575 5625);
DISPLAY INVISIBLE (-8575 5625);
FORCEPROP 1 LAST OFFPAGE TRUE
J 0
(-8250 5500);
DISPLAY 0.872340 (-8250 5500);
PAINT GREEN (-8250 5500);
DISPLAY INVISIBLE (-8250 5500);
FORCEPROP 1 LAST COMMENT_BODY TRUE
J 0
(-8450 5525);
DISPLAY 0.872340 (-8450 5525);
PAINT GREEN (-8450 5525);
DISPLAY INVISIBLE (-8450 5525);
FORCEPROP 2 LAST PATH I41
J 0
(-8775 5675);
DISPLAY 0.680851 (-8775 5675);
DISPLAY INVISIBLE (-8775 5675);
FORCEADD OFFPAGE..3
R 2
(-8575 5525);
FORCEPROP 2 LAST $XR1 34 
J 0
(-8914 5525);
DISPLAY 0.638298 (-8914 5525);
PAINT MONO (-8914 5525);
FORCEPROP 2 LAST $XR0 28 
J 0
(-8824 5525);
DISPLAY 0.638298 (-8824 5525);
PAINT MONO (-8824 5525);
FORCEPROP 2 LAST CDS_LIB standard
J 0
(-8575 5525);
DISPLAY INVISIBLE (-8575 5525);
FORCEPROP 1 LAST OFFPAGE TRUE
J 2
(-8900 5400);
DISPLAY 0.872340 (-8900 5400);
PAINT GREEN (-8900 5400);
DISPLAY INVISIBLE (-8900 5400);
FORCEPROP 1 LAST COMMENT_BODY TRUE
J 2
(-8525 5425);
DISPLAY 0.872340 (-8525 5425);
PAINT GREEN (-8525 5425);
DISPLAY INVISIBLE (-8525 5425);
FORCEPROP 2 LAST PATH I42
J 0
(-8800 5575);
DISPLAY 0.680851 (-8800 5575);
DISPLAY INVISIBLE (-8800 5575);
FORCEADD UNIVERSAL_POWER..1
R 2
(-7700 6300);
FORCEPROP 3 LASTPIN (-7700 6250) SIG_NAME PVDD18_S5_P0\g
J 0
(-7690 6260);
DISPLAY 0.659574 (-7690 6260);
PAINT MONO (-7690 6260);
DISPLAY INVISIBLE (-7690 6260);
FORCEPROP 1 LAST HDL_POWER PVDD18_S5_P0
J 1
(-7700 6350);
DISPLAY 0.489362 (-7700 6350);
PAINT GREEN (-7700 6350);
FORCEPROP 2 LAST CDS_LIB pure_quanta_power
J 0
(-7700 6300);
DISPLAY INVISIBLE (-7700 6300);
FORCEPROP 1 LAST PATH I43
J 2
(-7750 6325);
DISPLAY 0.872340 (-7750 6325);
PAINT AQUA (-7750 6325);
DISPLAY INVISIBLE (-7750 6325);
FORCEADD Q_CAP..1
(-7875 6025);
FORCEPROP 1 LAST LOCATION C42
J 0
(-7825 6125);
DISPLAY 0.489362 (-7825 6125);
PAINT SKYBLUE (-7825 6125);
FORCEPROP 0 LAST $SEC 1
J 0
(-7825 6175);
DISPLAY 0.680851 (-7825 6175);
PAINT MONO (-7825 6175);
DISPLAY INVISIBLE (-7825 6175);
FORCEPROP 0 LAST CDS_SEC 1
J 0
(-7825 6175);
DISPLAY 1.021277 (-7825 6175);
DISPLAY INVISIBLE (-7825 6175);
FORCEPROP 1 LASTPIN (-7875 6125) $PN 1
J 0
(-7865 6105);
DISPLAY 0.489362 (-7865 6105);
PAINT MONO (-7865 6105);
FORCEPROP 1 LASTPIN (-7875 5925) $PN 2
J 0
(-7865 5905);
DISPLAY 0.489362 (-7865 5905);
PAINT MONO (-7865 5905);
FORCEPROP 1 LAST MATERIAL X7R
J 2
(-7925 5975);
DISPLAY 0.489362 (-7925 5975);
PAINT SKYBLUE (-7925 5975);
FORCEPROP 1 LAST TOLERANCE 10%
J 2
(-7925 6025);
DISPLAY 0.489362 (-7925 6025);
PAINT SKYBLUE (-7925 6025);
FORCEPROP 1 LAST VALUE 0.1UF
J 2
(-7925 6125);
DISPLAY 0.489362 (-7925 6125);
PAINT SKYBLUE (-7925 6125);
FORCEPROP 1 LAST VOLTAGE 25V
J 2
(-7925 6075);
DISPLAY 0.489362 (-7925 6075);
PAINT SKYBLUE (-7925 6075);
FORCEPROP 1 LAST PACK_TYPE 0402
J 2
(-7925 5925);
DISPLAY 0.489362 (-7925 5925);
PAINT SKYBLUE (-7925 5925);
FORCEPROP 2 LAST CDS_LIB pure_quanta
J 0
(-7875 6025);
DISPLAY INVISIBLE (-7875 6025);
FORCEPROP 1 LAST PATH I44
J 0
(-7825 6175);
DISPLAY 0.978723 (-7825 6175);
PAINT WHITE (-7825 6175);
DISPLAY INVISIBLE (-7825 6175);
FORCEPROP 1 LAST PART_NUMBER CH4104K1B00
J 0
(-7825 5875);
DISPLAY 0.489362 (-7825 5875);
PAINT SKYBLUE (-7825 5875);
DISPLAY INVISIBLE (-7825 5875);
FORCEADD UNIVERSAL_GND..1
(-7875 5825);
FORCEPROP 3 LASTPIN (-7875 5875) SIG_NAME GND\g
J 0
(-7865 5885);
DISPLAY 0.659574 (-7865 5885);
PAINT MONO (-7865 5885);
DISPLAY INVISIBLE (-7865 5885);
FORCEPROP 2 LAST CDS_LIB pure_quanta_power
J 0
(-7875 5825);
DISPLAY INVISIBLE (-7875 5825);
FORCEPROP 1 LAST PATH I45
J 0
(-7800 5825);
DISPLAY 0.872340 (-7800 5825);
PAINT AQUA (-7800 5825);
DISPLAY INVISIBLE (-7800 5825);
FORCEPROP 1 LAST HDL_POWER GND
J 1
(-7850 5750);
DISPLAY 0.872340 (-7850 5750);
PAINT GREEN (-7850 5750);
DISPLAY INVISIBLE (-7850 5750);
FORCEADD UNIVERSAL_POWER..1
R 2
(-6625 6350);
FORCEPROP 3 LASTPIN (-6625 6300) SIG_NAME P3V3_STBY\g
J 0
(-6615 6310);
DISPLAY 0.659574 (-6615 6310);
PAINT MONO (-6615 6310);
DISPLAY INVISIBLE (-6615 6310);
FORCEPROP 1 LAST HDL_POWER P3V3_STBY
J 1
(-6625 6400);
DISPLAY 0.489362 (-6625 6400);
PAINT GREEN (-6625 6400);
FORCEPROP 2 LAST CDS_LIB pure_quanta_power
J 0
(-6625 6350);
DISPLAY INVISIBLE (-6625 6350);
FORCEPROP 1 LAST PATH I46
J 2
(-6675 6375);
DISPLAY 0.872340 (-6675 6375);
PAINT AQUA (-6675 6375);
DISPLAY INVISIBLE (-6675 6375);
FORCEADD Q_CAP..1
(-6550 6025);
FORCEPROP 1 LAST LOCATION C43
J 0
(-6500 6175);
DISPLAY 0.489362 (-6500 6175);
PAINT SKYBLUE (-6500 6175);
FORCEPROP 0 LAST $SEC 1
J 0
(-6500 6175);
DISPLAY 0.680851 (-6500 6175);
PAINT MONO (-6500 6175);
DISPLAY INVISIBLE (-6500 6175);
FORCEPROP 0 LAST CDS_SEC 1
J 0
(-6500 6175);
DISPLAY 1.021277 (-6500 6175);
DISPLAY INVISIBLE (-6500 6175);
FORCEPROP 1 LASTPIN (-6550 6125) $PN 1
J 0
(-6540 6105);
DISPLAY 0.489362 (-6540 6105);
PAINT MONO (-6540 6105);
FORCEPROP 1 LASTPIN (-6550 5925) $PN 2
J 0
(-6540 5905);
DISPLAY 0.489362 (-6540 5905);
PAINT MONO (-6540 5905);
FORCEPROP 1 LAST MATERIAL X7R
J 0
(-6500 5975);
DISPLAY 0.489362 (-6500 5975);
PAINT SKYBLUE (-6500 5975);
FORCEPROP 1 LAST TOLERANCE 10%
J 0
(-6500 6025);
DISPLAY 0.489362 (-6500 6025);
PAINT SKYBLUE (-6500 6025);
FORCEPROP 1 LAST VALUE 0.1UF
J 0
(-6500 6125);
DISPLAY 0.489362 (-6500 6125);
PAINT SKYBLUE (-6500 6125);
FORCEPROP 1 LAST VOLTAGE 25V
J 0
(-6500 6075);
DISPLAY 0.489362 (-6500 6075);
PAINT SKYBLUE (-6500 6075);
FORCEPROP 1 LAST PACK_TYPE 0402
J 0
(-6500 5925);
DISPLAY 0.489362 (-6500 5925);
PAINT SKYBLUE (-6500 5925);
FORCEPROP 2 LAST CDS_LIB pure_quanta
J 0
(-6550 6025);
DISPLAY INVISIBLE (-6550 6025);
FORCEPROP 1 LAST PATH I47
J 0
(-6500 6175);
DISPLAY 0.978723 (-6500 6175);
PAINT WHITE (-6500 6175);
DISPLAY INVISIBLE (-6500 6175);
FORCEPROP 1 LAST PART_NUMBER CH4104K1B00
J 0
(-6500 5875);
DISPLAY 0.489362 (-6500 5875);
PAINT SKYBLUE (-6500 5875);
DISPLAY INVISIBLE (-6500 5875);
FORCEADD UNIVERSAL_GND..1
(-6550 5825);
FORCEPROP 3 LASTPIN (-6550 5875) SIG_NAME GND\g
J 0
(-6540 5885);
DISPLAY 0.659574 (-6540 5885);
PAINT MONO (-6540 5885);
DISPLAY INVISIBLE (-6540 5885);
FORCEPROP 2 LAST CDS_LIB pure_quanta_power
J 0
(-6550 5825);
DISPLAY INVISIBLE (-6550 5825);
FORCEPROP 1 LAST PATH I48
J 0
(-6475 5825);
DISPLAY 0.872340 (-6475 5825);
PAINT AQUA (-6475 5825);
DISPLAY INVISIBLE (-6475 5825);
FORCEPROP 1 LAST HDL_POWER GND
J 1
(-6525 5750);
DISPLAY 0.872340 (-6525 5750);
PAINT GREEN (-6525 5750);
DISPLAY INVISIBLE (-6525 5750);
FORCEADD Q_RES..1
(-1675 5925);
FORCEPROP 1 LAST LOCATION R590
J 0
(-1925 5925);
DISPLAY 0.489362 (-1925 5925);
PAINT SKYBLUE (-1925 5925);
FORCEPROP 2 LAST $SEC 1
J 0
(-1725 6125);
DISPLAY 0.680851 (-1725 6125);
PAINT MONO (-1725 6125);
DISPLAY INVISIBLE (-1725 6125);
FORCEPROP 2 LAST CDS_SEC 1
J 0
(-1725 6125);
DISPLAY 0.680851 (-1725 6125);
DISPLAY INVISIBLE (-1725 6125);
FORCEPROP 1 LASTPIN (-1775 5925) $PN 1
J 0
(-1763 5937);
DISPLAY 0.489362 (-1763 5937);
PAINT MONO (-1763 5937);
FORCEPROP 1 LASTPIN (-1575 5925) $PN 2
J 0
(-1613 5937);
DISPLAY 0.489362 (-1613 5937);
PAINT MONO (-1613 5937);
FORCEPROP 1 LAST VALUE 4.7K
J 0
(-1550 5925);
DISPLAY 0.489362 (-1550 5925);
PAINT SKYBLUE (-1550 5925);
FORCEPROP 2 LAST CDS_LIB pure_quanta
J 0
(-1675 5925);
DISPLAY INVISIBLE (-1675 5925);
FORCEPROP 1 LAST PATH I5
J 0
(-1725 6075);
DISPLAY 0.978723 (-1725 6075);
PAINT WHITE (-1725 6075);
DISPLAY INVISIBLE (-1725 6075);
FORCEPROP 1 LAST WATTAGE 1/16W
J 2
(-1700 5775);
DISPLAY 0.510638 (-1700 5775);
PAINT SKYBLUE (-1700 5775);
DISPLAY INVISIBLE (-1700 5775);
FORCEPROP 1 LAST MATERIAL CHIP
J 0
(-1575 5900);
DISPLAY 0.489362 (-1575 5900);
PAINT SKYBLUE (-1575 5900);
DISPLAY INVISIBLE (-1575 5900);
FORCEPROP 1 LAST TOLERANCE 5%
J 0
(-1550 5925);
DISPLAY 0.510638 (-1550 5925);
PAINT SKYBLUE (-1550 5925);
DISPLAY INVISIBLE (-1550 5925);
FORCEPROP 1 LAST PART_NUMBER TMP_QCS24702JB38
J 0
(-1725 6025);
DISPLAY 0.510638 (-1725 6025);
PAINT SKYBLUE (-1725 6025);
DISPLAY INVISIBLE (-1725 6025);
FORCEPROP 1 LAST PACK_TYPE 0402LF
J 0
(-1425 5775);
DISPLAY 0.510638 (-1425 5775);
PAINT SKYBLUE (-1425 5775);
DISPLAY INVISIBLE (-1425 5775);
FORCEADD OFFPAGE..2
(-5825 5625);
FORCEPROP 2 LAST $XR1 79 
J 0
(-5546 5625);
DISPLAY 0.638298 (-5546 5625);
PAINT MONO (-5546 5625);
FORCEPROP 2 LAST $XR0 34 
J 0
(-5636 5625);
DISPLAY 0.638298 (-5636 5625);
PAINT MONO (-5636 5625);
FORCEPROP 2 LAST CDS_LIB standard
J 0
(-5825 5625);
DISPLAY INVISIBLE (-5825 5625);
FORCEPROP 1 LAST OFFPAGE TRUE
J 0
(-5500 5500);
DISPLAY 0.872340 (-5500 5500);
PAINT GREEN (-5500 5500);
DISPLAY INVISIBLE (-5500 5500);
FORCEPROP 1 LAST COMMENT_BODY TRUE
J 0
(-5870 5530);
DISPLAY 0.872340 (-5870 5530);
PAINT GREEN (-5870 5530);
DISPLAY INVISIBLE (-5870 5530);
FORCEPROP 2 LAST PATH I50
J 0
(-5525 5675);
DISPLAY 0.680851 (-5525 5675);
DISPLAY INVISIBLE (-5525 5675);
FORCEADD OFFPAGE..3
(-5825 5525);
FORCEPROP 2 LAST $XR1 79 
J 0
(-5521 5525);
DISPLAY 0.638298 (-5521 5525);
PAINT MONO (-5521 5525);
FORCEPROP 2 LAST $XR0 34 
J 0
(-5611 5525);
DISPLAY 0.638298 (-5611 5525);
PAINT MONO (-5611 5525);
FORCEPROP 2 LAST CDS_LIB standard
J 0
(-5825 5525);
DISPLAY INVISIBLE (-5825 5525);
FORCEPROP 1 LAST OFFPAGE TRUE
J 0
(-5500 5400);
DISPLAY 0.872340 (-5500 5400);
PAINT GREEN (-5500 5400);
DISPLAY INVISIBLE (-5500 5400);
FORCEPROP 1 LAST COMMENT_BODY TRUE
J 0
(-5875 5425);
DISPLAY 0.872340 (-5875 5425);
PAINT PEACH (-5875 5425);
DISPLAY INVISIBLE (-5875 5425);
FORCEPROP 2 LAST PATH I51
J 0
(-5500 5575);
DISPLAY 0.680851 (-5500 5575);
DISPLAY INVISIBLE (-5500 5575);
FORCEADD OFFPAGE..2
(-5250 2725);
FORCEPROP 2 LAST $XR0 80 
J 0
(-5061 2725);
DISPLAY 0.638298 (-5061 2725);
PAINT MONO (-5061 2725);
FORCEPROP 2 LAST CDS_LIB standard
J 0
(-5250 2725);
DISPLAY INVISIBLE (-5250 2725);
FORCEPROP 1 LAST OFFPAGE TRUE
J 0
(-4925 2600);
DISPLAY 0.872340 (-4925 2600);
PAINT GREEN (-4925 2600);
DISPLAY INVISIBLE (-4925 2600);
FORCEPROP 1 LAST COMMENT_BODY TRUE
J 0
(-5295 2630);
DISPLAY 0.872340 (-5295 2630);
PAINT GREEN (-5295 2630);
DISPLAY INVISIBLE (-5295 2630);
FORCEPROP 2 LAST PATH I52
J 0
(-5075 2800);
DISPLAY 0.680851 (-5075 2800);
DISPLAY INVISIBLE (-5075 2800);
FORCEADD Q_RES..2
(-5400 2975);
FORCEPROP 1 LAST LOCATION R943
J 0
(-5355 3100);
DISPLAY 0.489362 (-5355 3100);
PAINT SKYBLUE (-5355 3100);
FORCEPROP 0 LAST $SEC 1
J 0
(-5350 3150);
DISPLAY 0.680851 (-5350 3150);
PAINT MONO (-5350 3150);
DISPLAY INVISIBLE (-5350 3150);
FORCEPROP 0 LAST CDS_SEC 1
J 0
(-5350 3150);
DISPLAY 0.680851 (-5350 3150);
DISPLAY INVISIBLE (-5350 3150);
FORCEPROP 1 LASTPIN (-5400 3075) $PN 1
J 0
(-5395 3037);
DISPLAY 0.489362 (-5395 3037);
PAINT MONO (-5395 3037);
FORCEPROP 1 LASTPIN (-5400 2875) $PN 2
J 0
(-5395 2885);
DISPLAY 0.489362 (-5395 2885);
PAINT MONO (-5395 2885);
FORCEPROP 1 LAST WATTAGE 1/16W
J 0
(-5360 2950);
DISPLAY 0.489362 (-5360 2950);
PAINT SKYBLUE (-5360 2950);
FORCEPROP 1 LAST MATERIAL CHIP
J 0
(-5360 2900);
DISPLAY 0.489362 (-5360 2900);
PAINT SKYBLUE (-5360 2900);
FORCEPROP 1 LAST TOLERANCE 5%
J 0
(-5355 3000);
DISPLAY 0.489362 (-5355 3000);
PAINT SKYBLUE (-5355 3000);
FORCEPROP 1 LAST VALUE 4.7K
J 0
(-5355 3050);
DISPLAY 0.489362 (-5355 3050);
PAINT SKYBLUE (-5355 3050);
FORCEPROP 1 LAST PART_NUMBER TMP_QCS24702JB38
J 0
(-5360 2850);
DISPLAY 0.489362 (-5360 2850);
PAINT SKYBLUE (-5360 2850);
FORCEPROP 1 LAST PACK_TYPE 0402LF
J 0
(-5360 2800);
DISPLAY 0.489362 (-5360 2800);
PAINT SKYBLUE (-5360 2800);
FORCEPROP 2 LAST CDS_LIB pure_quanta
J 0
(-5400 2975);
DISPLAY INVISIBLE (-5400 2975);
FORCEPROP 2 LAST BOM_COST OCP3.0 
J 0
(-5350 3150);
DISPLAY 0.680851 (-5350 3150);
DISPLAY INVISIBLE (-5350 3150);
FORCEPROP 1 LAST PATH I53
J 0
(-5350 3150);
DISPLAY 0.978723 (-5350 3150);
PAINT WHITE (-5350 3150);
DISPLAY INVISIBLE (-5350 3150);
FORCEADD UNIVERSAL_POWER..1
(-5400 3250);
FORCEPROP 3 LASTPIN (-5400 3200) SIG_NAME P1V8_STBY\g
J 0
(-5390 3210);
DISPLAY 0.659574 (-5390 3210);
PAINT MONO (-5390 3210);
DISPLAY INVISIBLE (-5390 3210);
FORCEPROP 1 LAST HDL_POWER P1V8_STBY
J 1
(-5400 3300);
DISPLAY 0.489362 (-5400 3300);
PAINT GREEN (-5400 3300);
FORCEPROP 2 LAST BOM_COST OCP3.0 
J 0
(-5400 3350);
DISPLAY 0.680851 (-5400 3350);
DISPLAY INVISIBLE (-5400 3350);
FORCEPROP 2 LAST CDS_LIB pure_quanta_power
J 0
(-5400 3250);
DISPLAY INVISIBLE (-5400 3250);
FORCEPROP 1 LAST PATH I54
J 0
(-5350 3275);
DISPLAY 0.872340 (-5350 3275);
PAINT AQUA (-5350 3275);
DISPLAY INVISIBLE (-5350 3275);
FORCEADD SN74LVC1G07DBVR..1
(-6350 2725);
FORCEPROP 1 LAST LOCATION U101
J 0
(-6475 2980);
DISPLAY 0.489362 (-6475 2980);
PAINT SKYBLUE (-6475 2980);
FORCEPROP 0 LAST $SEC 1
J 0
(-6475 3125);
DISPLAY 0.680851 (-6475 3125);
PAINT MONO (-6475 3125);
DISPLAY INVISIBLE (-6475 3125);
FORCEPROP 0 LAST CDS_SEC 1
J 0
(-6475 3125);
DISPLAY 0.680851 (-6475 3125);
DISPLAY INVISIBLE (-6475 3125);
FORCEPROP 0 LASTPIN (-6525 2725) $PN 2
J 2
(-6535 2735);
DISPLAY 0.489362 (-6535 2735);
PAINT MONO (-6535 2735);
FORCEPROP 0 LASTPIN (-6525 2625) $PN 3
J 2
(-6535 2635);
DISPLAY 0.489362 (-6535 2635);
PAINT MONO (-6535 2635);
FORCEPROP 0 LASTPIN (-6175 2625) $PN 1
J 0
(-6165 2635);
DISPLAY 0.489362 (-6165 2635);
PAINT MONO (-6165 2635);
FORCEPROP 0 LASTPIN (-6525 2825) $PN 5
J 2
(-6535 2835);
DISPLAY 0.489362 (-6535 2835);
PAINT MONO (-6535 2835);
FORCEPROP 0 LASTPIN (-6175 2725) $PN 4
J 0
(-6165 2735);
DISPLAY 0.489362 (-6165 2735);
PAINT MONO (-6165 2735);
FORCEPROP 1 LAST MATERIAL IC
J 0
(-6475 2885);
DISPLAY 0.489362 (-6475 2885);
PAINT SKYBLUE (-6475 2885);
FORCEPROP 2 LAST VALUE SN74LVC1G07DBVR
J 0
(-6475 3075);
DISPLAY 0.489362 (-6475 3075);
PAINT SKYBLUE (-6475 3075);
FORCEPROP 1 LAST PART_NUMBER AL1G0007024
J 0
(-6475 2935);
DISPLAY 0.489362 (-6475 2935);
PAINT SKYBLUE (-6475 2935);
FORCEPROP 2 LAST PACK_TYPE SMLF
J 0
(-6475 3025);
DISPLAY 0.489362 (-6475 3025);
PAINT SKYBLUE (-6475 3025);
FORCEPROP 2 LAST CDS_LIB pure_quanta
J 0
(-6350 2725);
DISPLAY INVISIBLE (-6350 2725);
FORCEPROP 1 LAST NEEDS_NO_SIZE TRUE
J 0
(-6350 2725);
DISPLAY 0.468085 (-6350 2725);
PAINT GREEN (-6350 2725);
DISPLAY INVISIBLE (-6350 2725);
FORCEPROP 1 LAST PATH I55
J 0
(-6250 2880);
DISPLAY 0.723404 (-6250 2880);
PAINT GREEN (-6250 2880);
DISPLAY INVISIBLE (-6250 2880);
FORCEADD UNIVERSAL_GND..1
(-6600 2450);
FORCEPROP 3 LASTPIN (-6600 2500) SIG_NAME GND\g
J 0
(-6590 2510);
DISPLAY 0.659574 (-6590 2510);
PAINT MONO (-6590 2510);
DISPLAY INVISIBLE (-6590 2510);
FORCEPROP 2 LAST BOM_COST OCP3.0 
J 0
(-6800 2525);
DISPLAY 0.680851 (-6800 2525);
DISPLAY INVISIBLE (-6800 2525);
FORCEPROP 2 LAST CDS_LIB pure_quanta_power
J 0
(-6600 2450);
DISPLAY INVISIBLE (-6600 2450);
FORCEPROP 1 LAST PATH I56
J 0
(-6525 2450);
DISPLAY 0.872340 (-6525 2450);
PAINT AQUA (-6525 2450);
DISPLAY INVISIBLE (-6525 2450);
FORCEPROP 1 LAST HDL_POWER GND
J 1
(-6575 2375);
DISPLAY 0.872340 (-6575 2375);
PAINT GREEN (-6575 2375);
DISPLAY INVISIBLE (-6575 2375);
FORCEADD UNIVERSAL_GND..1
(-6950 2850);
FORCEPROP 3 LASTPIN (-6950 2900) SIG_NAME GND\g
J 0
(-6940 2910);
DISPLAY 0.659574 (-6940 2910);
PAINT MONO (-6940 2910);
DISPLAY INVISIBLE (-6940 2910);
FORCEPROP 2 LAST BOM_COST OCP3.0 
J 0
(-7150 2925);
DISPLAY 0.680851 (-7150 2925);
DISPLAY INVISIBLE (-7150 2925);
FORCEPROP 2 LAST CDS_LIB pure_quanta_power
J 0
(-6950 2850);
DISPLAY INVISIBLE (-6950 2850);
FORCEPROP 1 LAST PATH I58
J 0
(-6875 2850);
DISPLAY 0.872340 (-6875 2850);
PAINT AQUA (-6875 2850);
DISPLAY INVISIBLE (-6875 2850);
FORCEPROP 1 LAST HDL_POWER GND
J 1
(-6925 2775);
DISPLAY 0.872340 (-6925 2775);
PAINT GREEN (-6925 2775);
DISPLAY INVISIBLE (-6925 2775);
FORCEADD Q_CAP..1
(-6950 3050);
FORCEPROP 1 LAST LOCATION C226
J 0
(-6900 3150);
DISPLAY 0.489362 (-6900 3150);
PAINT SKYBLUE (-6900 3150);
FORCEPROP 0 LAST $SEC 1
J 0
(-6900 3200);
DISPLAY 0.680851 (-6900 3200);
PAINT MONO (-6900 3200);
DISPLAY INVISIBLE (-6900 3200);
FORCEPROP 0 LAST CDS_SEC 1
J 0
(-6900 3200);
DISPLAY 0.680851 (-6900 3200);
DISPLAY INVISIBLE (-6900 3200);
FORCEPROP 1 LASTPIN (-6950 3150) $PN 1
J 0
(-6940 3130);
DISPLAY 0.489362 (-6940 3130);
PAINT MONO (-6940 3130);
FORCEPROP 1 LASTPIN (-6950 2950) $PN 2
J 0
(-6940 2930);
DISPLAY 0.489362 (-6940 2930);
PAINT MONO (-6940 2930);
FORCEPROP 1 LAST MATERIAL X7R
J 0
(-6875 2975);
DISPLAY 0.489362 (-6875 2975);
PAINT SKYBLUE (-6875 2975);
FORCEPROP 1 LAST TOLERANCE 10%
J 0
(-6875 3025);
DISPLAY 0.489362 (-6875 3025);
PAINT SKYBLUE (-6875 3025);
FORCEPROP 1 LAST VALUE 0.1UF
J 0
(-6875 3125);
DISPLAY 0.489362 (-6875 3125);
PAINT SKYBLUE (-6875 3125);
FORCEPROP 1 LAST PART_NUMBER CH4104K1B00
J 0
(-6875 2925);
DISPLAY 0.489362 (-6875 2925);
PAINT SKYBLUE (-6875 2925);
FORCEPROP 1 LAST VOLTAGE 25V
J 0
(-6875 3075);
DISPLAY 0.489362 (-6875 3075);
PAINT SKYBLUE (-6875 3075);
FORCEPROP 1 LAST PACK_TYPE 0402
J 0
(-6875 2875);
DISPLAY 0.489362 (-6875 2875);
PAINT SKYBLUE (-6875 2875);
FORCEPROP 2 LAST CDS_LIB pure_quanta
J 0
(-6950 3050);
DISPLAY INVISIBLE (-6950 3050);
FORCEPROP 2 LAST BOM_COST OCP3.0 
J 0
(-6925 3175);
DISPLAY 0.680851 (-6925 3175);
DISPLAY INVISIBLE (-6925 3175);
FORCEPROP 1 LAST PATH I59
J 0
(-6900 3200);
DISPLAY 0.978723 (-6900 3200);
PAINT WHITE (-6900 3200);
DISPLAY INVISIBLE (-6900 3200);
FORCEADD Q_RES..2
R 2
(-7075 3050);
FORCEPROP 1 LAST LOCATION R942
J 2
(-7120 3175);
DISPLAY 0.489362 (-7120 3175);
PAINT SKYBLUE (-7120 3175);
FORCEPROP 0 LAST $SEC 1
J 0
(-7100 3225);
DISPLAY 0.680851 (-7100 3225);
PAINT MONO (-7100 3225);
DISPLAY INVISIBLE (-7100 3225);
FORCEPROP 0 LAST CDS_SEC 1
J 0
(-7100 3225);
DISPLAY 0.680851 (-7100 3225);
DISPLAY INVISIBLE (-7100 3225);
FORCEPROP 1 LASTPIN (-7075 3150) $PN 1
J 2
(-7080 3112);
DISPLAY 0.489362 (-7080 3112);
PAINT MONO (-7080 3112);
FORCEPROP 1 LASTPIN (-7075 2950) $PN 2
J 2
(-7080 2960);
DISPLAY 0.489362 (-7080 2960);
PAINT MONO (-7080 2960);
FORCEPROP 1 LAST WATTAGE 1/16W
J 2
(-7115 3025);
DISPLAY 0.489362 (-7115 3025);
PAINT SKYBLUE (-7115 3025);
FORCEPROP 1 LAST MATERIAL CHIP
J 2
(-7115 2975);
DISPLAY 0.489362 (-7115 2975);
PAINT SKYBLUE (-7115 2975);
FORCEPROP 1 LAST TOLERANCE 5%
J 2
(-7120 3075);
DISPLAY 0.489362 (-7120 3075);
PAINT SKYBLUE (-7120 3075);
FORCEPROP 1 LAST VALUE 4.7K
J 2
(-7120 3125);
DISPLAY 0.489362 (-7120 3125);
PAINT SKYBLUE (-7120 3125);
FORCEPROP 1 LAST PART_NUMBER TMP_QCS24702JB38
J 2
(-7115 2925);
DISPLAY 0.489362 (-7115 2925);
PAINT SKYBLUE (-7115 2925);
FORCEPROP 1 LAST PACK_TYPE 0402LF
J 2
(-7115 2875);
DISPLAY 0.489362 (-7115 2875);
PAINT SKYBLUE (-7115 2875);
FORCEPROP 2 LAST CDS_LIB pure_quanta
J 0
(-7075 3050);
DISPLAY INVISIBLE (-7075 3050);
FORCEPROP 2 LAST BOM_COST OCP3.0 
J 2
(-7125 3225);
DISPLAY 0.680851 (-7125 3225);
DISPLAY INVISIBLE (-7125 3225);
FORCEPROP 1 LAST PATH I60
J 2
(-7125 3225);
DISPLAY 0.978723 (-7125 3225);
PAINT WHITE (-7125 3225);
DISPLAY INVISIBLE (-7125 3225);
FORCEADD OFFPAGE..1
(-8650 2725);
FORCEPROP 2 LAST $XR1 143 
J 0
(-8991 2725);
DISPLAY 0.638298 (-8991 2725);
PAINT MONO (-8991 2725);
FORCEPROP 2 LAST $XR0 28 
J 0
(-8871 2725);
DISPLAY 0.638298 (-8871 2725);
PAINT MONO (-8871 2725);
FORCEPROP 2 LAST CDS_LIB standard
J 0
(-8650 2725);
DISPLAY INVISIBLE (-8650 2725);
FORCEPROP 1 LAST OFFPAGE TRUE
J 0
(-8325 2600);
DISPLAY 0.872340 (-8325 2600);
PAINT GREEN (-8325 2600);
DISPLAY INVISIBLE (-8325 2600);
FORCEPROP 1 LAST COMMENT_BODY TRUE
J 0
(-8525 2625);
DISPLAY 0.872340 (-8525 2625);
PAINT GREEN (-8525 2625);
DISPLAY INVISIBLE (-8525 2625);
FORCEPROP 2 LAST PATH I61
J 0
(-8600 2800);
DISPLAY 0.680851 (-8600 2800);
DISPLAY INVISIBLE (-8600 2800);
FORCEADD P1V0..1
(-6950 3350);
FORCEPROP 3 LASTPIN (-6950 3300) SIG_NAME PVDD18_S5_P0\g
J 0
(-6940 3310);
DISPLAY 0.659574 (-6940 3310);
PAINT MONO (-6940 3310);
DISPLAY INVISIBLE (-6940 3310);
FORCEPROP 1 LAST HDL_POWER PVDD18_S5_P0
J 1
(-6950 3400);
DISPLAY 0.489362 (-6950 3400);
PAINT GREEN (-6950 3400);
FORCEPROP 2 LAST CDS_LIB pure_quanta_power
J 0
(-6950 3350);
DISPLAY INVISIBLE (-6950 3350);
FORCEPROP 1 LAST PATH I62
J 0
(-6900 3375);
DISPLAY 0.872340 (-6900 3375);
PAINT AQUA (-6900 3375);
DISPLAY INVISIBLE (-6900 3375);
FORCEADD QUANTA_TITLE_BLOCK_C..1
(0 0);
FORCEPROP 0 LAST CDS_CON_LAST_MODIFIED Fri Mar 11 14:52:28 2022
J 0
(-1885 15);
DISPLAY INVISIBLE (-1885 15);
FORCEPROP 1 LAST CUSTOM_TXT_CDS <CON_LAST_MODIFIED>
J 0
(-1885 15);
DISPLAY 0.978723 (-1885 15);
FORCEPROP 2 LAST CUSTOM_TXT_CDS <XR_PAGE_TITLE>
J 0
(-7890 5250);
DISPLAY 0.638298 (-7890 5250);
PAINT PINK (-7890 5250);
DISPLAY INVISIBLE (-7890 5250);
FORCEPROP 1 LAST CUSTOM_TXT_CDS <NAME_2>
J 0
(-3175 50);
FORCEPROP 1 LAST CUSTOM_TXT_CDS <NAME_1>
J 0
(-3175 175);
FORCEPROP 1 LAST CUSTOM_TXT_CDS <Q_NUMBER>
J 0
(-1403 103);
DISPLAY 1.212766 (-1403 103);
FORCEPROP 1 LAST CUSTOM_TXT_CDS <Q_PROJ>
J 0
(-2382 102);
DISPLAY 1.212766 (-2382 102);
FORCEPROP 1 LAST CUSTOM_TXT_CDS <Q_REV>
J 0
(-184 103);
DISPLAY 1.212766 (-184 103);
FORCEPROP 1 LAST CUSTOM_TXT_CDS <CON_PAGE_NUM> OF <CON_TOTAL_PAGES>
J 0
(-446 18);
DISPLAY 0.978723 (-446 18);
FORCEPROP 1 LAST Q_DEPT BU9
J 1
(-3763 49);
DISPLAY 1.957447 (-3763 49);
PAINT GREEN (-3763 49);
FORCEPROP 1 LAST Q_TITLE CPU0 GLUE LOGIC
J 0
(-9275 75);
DISPLAY 2.446809 (-9275 75);
PAINT GREEN (-9275 75);
FORCEPROP 2 LAST PAGE_BORDER TRUE
J 0
(-7890 5250);
DISPLAY 0.638298 (-7890 5250);
PAINT PINK (-7890 5250);
DISPLAY INVISIBLE (-7890 5250);
FORCEPROP 1 LAST CDS_LMAN_SYM_OUTLINE -9475,6775,100,-125
J 0
(0 0);
DISPLAY 0.468085 (0 0);
PAINT GREEN (0 0);
DISPLAY INVISIBLE (0 0);
FORCEPROP 2 LAST CDS_LIB pure_quanta
J 0
(0 0);
DISPLAY INVISIBLE (0 0);
FORCEPROP 1 LAST COMMENT_BODY TRUE
J 0
(12 -13);
DISPLAY 0.978723 (12 -13);
PAINT GREEN (12 -13);
DISPLAY INVISIBLE (12 -13);
FORCEPROP 2 LAST CDS_XR_PAGE_TITLE CR-34 : @T6G_MB_LIB.T6G(SCH_1):PAGE34
J 0
(-7890 5250);
DISPLAY 0.638298 (-7890 5250);
PAINT PINK (-7890 5250);
DISPLAY INVISIBLE (-7890 5250);
WIRE 16 -1 (-6750 4325)(-6750 4275);
WIRE 16 -1 (-7675 4125)(-7625 4125);
WIRE 16 -1 (-7775 5375)(-7625 5375);
WIRE 16 -1 (-7775 5375)(-7775 5225);
WIRE 16 -1 (-7875 5925)(-7875 5875);
WIRE 16 -1 (-6550 5925)(-6550 5875);
WIRE 16 -1 (-5400 3075)(-5400 3200);
WIRE 16 -1 (-6525 2625)(-6600 2625);
WIRE 16 -1 (-6600 2625)(-6600 2500);
WIRE 16 -1 (-6950 2900)(-6950 2950);
WIRE 16 -1 (-8525 4175)(-7625 4175);
FORCEPROP 2 LAST SIG_NAME SLOT1_SKU_ID0
J 0
(-8200 4185);
DISPLAY 0.489362 (-8200 4185);
WIRE 16 -1 (-8525 4075)(-7625 4075);
FORCEPROP 2 LAST SIG_NAME SLOT1_SKU_ID1
J 0
(-8200 4085);
DISPLAY 0.489362 (-8200 4085);
WIRE 16 -1 (-7625 5625)(-8525 5625);
FORCEPROP 2 LAST SIG_NAME SMB_CPU0_4_SCL
J 2
(-7960 5635);
DISPLAY 0.489362 (-7960 5635);
WIRE 16 -1 (-7625 5525)(-8525 5525);
FORCEPROP 2 LAST SIG_NAME SMB_CPU0_4_SDA
J 2
(-7960 5535);
DISPLAY 0.489362 (-7960 5535);
WIRE 16 -1 (-8600 2725)(-7075 2725);
FORCEPROP 2 LAST SIG_NAME FM_BIOS_POST_CMPLT_N
J 0
(-7710 2735);
DISPLAY 0.489362 (-7710 2735);
WIRE 16 -1 (-6525 2725)(-7075 2725);
WIRE 16 -1 (-7075 2725)(-7075 2950);
WIRE 16 -1 (-6600 3200)(-6600 2825);
WIRE 16 -1 (-6950 3200)(-6600 3200);
WIRE 16 -1 (-6600 2825)(-6525 2825);
WIRE 16 -1 (-6950 3300)(-6950 3200);
WIRE 16 -1 (-6950 3200)(-6950 3150);
WIRE 16 -1 (-6950 3200)(-7075 3200);
WIRE 16 -1 (-7075 3150)(-7075 3200);
WIRE 16 -1 (-6975 4075)(-6075 4075);
FORCEPROP 2 LAST SIG_NAME SLOT1_BUF_SKU_ID1
J 0
(-6650 4085);
DISPLAY 0.489362 (-6650 4085);
WIRE 16 -1 (-6175 2725)(-5400 2725);
FORCEPROP 2 LAST SIG_NAME FM_BIOS_POST_CMPLT_BUF_N
J 0
(-6035 2735);
DISPLAY 0.489362 (-6035 2735);
WIRE 16 -1 (-5400 2725)(-5300 2725);
WIRE 16 -1 (-5400 2725)(-5400 2875);
WIRE 16 -1 (-6975 4125)(-6825 4125);
WIRE 16 -1 (-6825 4600)(-6825 4125);
WIRE 16 -1 (-6825 4700)(-6825 4600);
WIRE 16 -1 (-6750 4600)(-6825 4600);
WIRE 16 -1 (-6750 4525)(-6750 4600);
WIRE 16 -1 (-6775 5375)(-6425 5375);
FORCEPROP 2 LAST SIG_NAME TP_U27_EN
J 0
(-6635 5385);
DISPLAY 0.489362 (-6635 5385);
FORCEPROP 2 LASTPROP $XRERR UNIQUE?
J 0
(-6395 5375);
DISPLAY 0.638298 (-6395 5375);
PAINT MONO (-6395 5375);
DISPLAY INVISIBLE (-6395 5375);
WIRE 16 -1 (-6775 5775)(-6625 5775);
WIRE 16 -1 (-6625 6200)(-6625 5775);
WIRE 16 -1 (-6625 6300)(-6625 6200);
WIRE 16 -1 (-6550 6200)(-6625 6200);
WIRE 16 -1 (-6550 6125)(-6550 6200);
WIRE 16 -1 (-7625 5775)(-7700 5775);
WIRE 16 -1 (-7700 5775)(-7700 6200);
WIRE 16 -1 (-7700 6250)(-7700 6200);
WIRE 16 -1 (-7875 6200)(-7700 6200);
WIRE 16 -1 (-7875 6125)(-7875 6200);
WIRE 16 -1 (-6975 4175)(-6075 4175);
FORCEPROP 2 LAST SIG_NAME SLOT1_BUF_SKU_ID0
J 0
(-6650 4185);
DISPLAY 0.489362 (-6650 4185);
WIRE 16 -1 (-6775 5625)(-5875 5625);
FORCEPROP 2 LAST SIG_NAME SMB_CPU0_4_XLTR_SCL
J 2
(-6210 5635);
DISPLAY 0.489362 (-6210 5635);
WIRE 16 -1 (-6775 5525)(-5875 5525);
FORCEPROP 2 LAST SIG_NAME SMB_CPU0_4_XLTR_SDA
J 2
(-6210 5535);
DISPLAY 0.489362 (-6210 5535);
WIRE 16 -1 (-2025 4850)(-1725 4850);
WIRE 16 -1 (-2025 4925)(-2025 4850);
WIRE 16 -1 (-2025 4925)(-1725 4925);
WIRE 16 -1 (-2025 5100)(-2025 4925);
WIRE 16 -1 (-2025 5200)(-2025 5100);
WIRE 16 -1 (-2025 5100)(-1725 5100);
WIRE 16 -1 (-2025 5200)(-1725 5200);
WIRE 16 -1 (-2025 5350)(-2025 5200);
WIRE 16 -1 (-2025 5925)(-1775 5925);
WIRE 16 -1 (-2025 6000)(-2025 5925);
WIRE 16 -1 (-2025 6425)(-2025 6000);
WIRE 16 -1 (-2025 6000)(-1775 6000);
WIRE 16 -1 (-1575 5925)(-650 5925);
FORCEPROP 2 LAST SIG_NAME SMB_CPU0_4_XLTR_SDA
J 2
(-985 5935);
DISPLAY 0.489362 (-985 5935);
WIRE 16 -1 (-575 4925)(-1525 4925);
FORCEPROP 2 LAST SIG_NAME SMB_CPU0_4_SCL
J 0
(-1325 4935);
DISPLAY 0.489362 (-1325 4935);
WIRE 16 -1 (-1525 4850)(-575 4850);
FORCEPROP 2 LAST SIG_NAME SMB_CPU0_4_SDA
J 0
(-1325 4860);
DISPLAY 0.489362 (-1325 4860);
WIRE 16 -1 (-1525 5200)(-575 5200);
FORCEPROP 2 LAST SIG_NAME SLOT1_BUF_SKU_ID0
J 0
(-1325 5210);
DISPLAY 0.489362 (-1325 5210);
WIRE 16 -1 (-1525 5100)(-575 5100);
FORCEPROP 2 LAST SIG_NAME SLOT1_BUF_SKU_ID1
J 0
(-1325 5110);
DISPLAY 0.489362 (-1325 5110);
WIRE 16 -1 (-1575 6000)(-650 6000);
FORCEPROP 2 LAST SIG_NAME SMB_CPU0_4_XLTR_SCL
J 2
(-985 6010);
DISPLAY 0.489362 (-985 6010);
DOT 1 (-6950 3200);
DOT 1 (-5400 2725);
DOT 1 (-6825 4600);
DOT 1 (-2025 5100);
DOT 1 (-2025 4925);
DOT 1 (-2025 5200);
DOT 1 (-2025 6000);
DOT 1 (-7700 6200);
DOT 1 (-6625 6200);
DOT 1 (-7075 2725);
FORCENOTE
INTERNAL PU
(-7400 5100) 0;
DISPLAY LEFT (-7400 5100);
DISPLAY 1.021277 (-7400 5100);
QUIT
